# S9S_MB_2U (Grand Teton) — schematic netlist excerpt (pin names and nets, part order shuffled) for the footprints in the layout excerpt that follows; sources: Cadence DE-HDL packaged netlist, KiCad conversion of 03242023_DA0F0TMBIJ0_F0T_Motherboard_J_brd_V01_OCP.brd

PR1791  Q_RES  3.3 1% CHIP  pkg 0402LF  page 287 : A = SW_PVCCIN_CPU1_BOOT5 ; B = SW_PVCCIN_CPU1_BOOT5_R

U86  74CBTLV3126PW  IC  pkg TSSOP14  page 134
  \1oe\  = PD_JTAG_BMC_NTRST_N
  \1a\  = FM_BMC_EN_DET
  \1b\  = TP_JTAG_BMC_1B
  \2oe\  = JTAG_BMC_CPU_TCK
  \2a\  = FM_BMC_EN_DET
  \2b\  = JTAG_DBP_CPU_GTL_TCK_R1
  GND  = GND
  \3b\  = JTAG_DBP_TCK_PCH_R
  \3a\  = FM_BMC_EN_DET
  \3oe\  = JTAG_BMC_PCH_TCK
  \4b\  = TP_JTAG_BMC_4B
  \4a\  = FM_BMC_EN_DET
  \4oe\  = PD_JTAG_BMC_NTRST_N
  VCC  = P3V3_AUX

(kicad_pcb
	(version 20260206)
	(generator "pcbnew")
	(generator_version "10.0")
	(general
		(thickness 1.6)
		(legacy_teardrops no)
	)
	(paper "A4")
	(title_block
		(title "03242023_DA0F0TMBIJ0_F0T_Motherboard_J_brd_V01_OCP.brd")
		(comment 1 "Grand Teton / footprints 594-595 of 6105")
	)
	(layers
		(0 "F.Cu" signal "TOP")
		(4 "In1.Cu" signal "GND")
		(6 "In2.Cu" signal "IN1")
		(8 "In3.Cu" signal "GND1")
		(10 "In4.Cu" signal "IN2")
		(12 "In5.Cu" signal "GND2")
		(14 "In6.Cu" signal "IN3")
		(16 "In7.Cu" signal "GND3")
		(18 "In8.Cu" signal "VCC")
		(20 "In9.Cu" signal "VCC1")
		(22 "In10.Cu" signal "GND4")
		(24 "In11.Cu" signal "IN4")
		(26 "In12.Cu" signal "GND5")
		(28 "In13.Cu" signal "IN5")
		(30 "In14.Cu" signal "GND6")
		(32 "In15.Cu" signal "IN6")
		(34 "In16.Cu" signal "GND7")
		(2 "B.Cu" signal "BOTTOM")
		(9 "F.Adhes" user "F.Adhesive")
		(11 "B.Adhes" user "B.Adhesive")
		(13 "F.Paste" user "Package Geometry/Pastemask Top")
		(15 "B.Paste" user "Package Geometry/Pastemask Bottom")
		(5 "F.SilkS" user "Ref Des/Silkscreen Top")
		(7 "B.SilkS" user "Ref Des/Silkscreen Bottom")
		(1 "F.Mask" user "Board Geometry/Soldermask Top")
		(3 "B.Mask" user "Board Geometry/Soldermask Bottom")
		(17 "Dwgs.User" user "User.Drawings")
		(19 "Cmts.User" user "User.Comments")
		(21 "Eco1.User" user "User.Eco1")
		(23 "Eco2.User" user "User.Eco2")
		(25 "Edge.Cuts" user "Board Geometry/Outline")
		(27 "Margin" user)
		(31 "F.CrtYd" user "Package Geometry/Place Bound Top")
		(29 "B.CrtYd" user "Package Geometry/Place Bound Bottom")
		(35 "F.Fab" user "Ref Des/Assembly Top")
		(33 "B.Fab" user "Ref Des/Assembly Bottom")
	)
	(footprint ""
		(layer "F.Cu")
		(at 102.84841 -55.277004)
		(property "Reference" "U86"
			(at -2.032 -3.27533 0)
			(unlocked yes)
			(layer "F.SilkS")
			(effects
				(font
					(size 0.7874 0.5842)
					(thickness 0.1524)
				)
				(justify left)
			)
		)
		(property "Value" ""
			(at 0 0 0)
			(layer "F.Fab")
			(effects
				(font
					(size 1.27 1.27)
				)
			)
		)
		(duplicate_pad_numbers_are_jumpers no)
		(fp_line
			(start -2.0066 -2.5527)
			(end -0.5715 -2.5527)
			(stroke
				(width 0.1524)
				(type default)
			)
			(layer "F.SilkS")
		)
		(fp_line
			(start -2.0066 2.5527)
			(end -2.0066 -2.5527)
			(stroke
				(width 0.1524)
				(type default)
			)
			(layer "F.SilkS")
		)
		(fp_line
			(start -0.5715 -2.5527)
			(end 0 -1.9812)
			(stroke
				(width 0.1524)
				(type default)
			)
			(layer "F.SilkS")
		)
		(fp_line
			(start 0 -1.9812)
			(end 0.5715 -2.5527)
			(stroke
				(width 0.1524)
				(type default)
			)
			(layer "F.SilkS")
		)
		(fp_line
			(start 0.5715 -2.5527)
			(end 2.0066 -2.5527)
			(stroke
				(width 0.1524)
				(type default)
			)
			(layer "F.SilkS")
		)
		(fp_line
			(start 2.0066 -2.5527)
			(end 2.0066 2.5527)
			(stroke
				(width 0.1524)
				(type default)
			)
			(layer "F.SilkS")
		)
		(fp_line
			(start 2.0066 2.5527)
			(end -2.0066 2.5527)
			(stroke
				(width 0.1524)
				(type default)
			)
			(layer "F.SilkS")
		)
		(fp_poly
			(pts
				(xy -2.669286 -2.982214) (xy -2.997454 -2.428494) (xy -3.294126 -2.982214)
			)
			(stroke
				(width 0)
				(type default)
			)
			(fill yes)
			(layer "F.SilkS")
		)
		(fp_line
			(start -2.249932 -2.549906)
			(end 2.249932 -2.549906)
			(stroke
				(width 0.1)
				(type default)
			)
			(layer "F.Fab")
		)
		(fp_line
			(start -2.249932 2.549906)
			(end -2.249932 -2.549906)
			(stroke
				(width 0.1)
				(type default)
			)
			(layer "F.Fab")
		)
		(fp_line
			(start 2.249932 -2.549906)
			(end 2.249932 2.549906)
			(stroke
				(width 0.1)
				(type default)
			)
			(layer "F.Fab")
		)
		(fp_line
			(start 2.249932 2.549906)
			(end -2.249932 2.549906)
			(stroke
				(width 0.1)
				(type default)
			)
			(layer "F.Fab")
		)
		(fp_poly
			(pts
				(xy -4.36372 -1.608328) (xy -4.36372 -2.233168) (xy -3.81 -1.905)
			)
			(stroke
				(width 0)
				(type default)
			)
			(fill yes)
			(layer "F.Fab")
		)
		(pad "1" smd rect
			(at -2.921 -1.949958 270)
			(size 0.3556 1.4986)
			(layers "F.Cu" "F.Mask" "F.Paste")
			(net "PD_JTAG_BMC_NTRST_N")
		)
		(pad "2" smd rect
			(at -2.921 -1.299972 270)
			(size 0.3556 1.4986)
			(layers "F.Cu" "F.Mask" "F.Paste")
			(net "FM_BMC_EN_DET")
		)
		(pad "3" smd rect
			(at -2.921 -0.649986 270)
			(size 0.3556 1.4986)
			(layers "F.Cu" "F.Mask" "F.Paste")
			(net "TP_JTAG_BMC_1B")
		)
		(pad "4" smd rect
			(at -2.921 0 270)
			(size 0.3556 1.4986)
			(layers "F.Cu" "F.Mask" "F.Paste")
			(net "JTAG_BMC_CPU_TCK")
		)
		(pad "5" smd rect
			(at -2.921 0.649986 270)
			(size 0.3556 1.4986)
			(layers "F.Cu" "F.Mask" "F.Paste")
			(net "FM_BMC_EN_DET")
		)
		(pad "6" smd rect
			(at -2.921 1.299972 270)
			(size 0.3556 1.4986)
			(layers "F.Cu" "F.Mask" "F.Paste")
			(net "JTAG_DBP_CPU_GTL_TCK_R1")
		)
		(pad "7" smd rect
			(at -2.921 1.949958 270)
			(size 0.3556 1.4986)
			(layers "F.Cu" "F.Mask" "F.Paste")
			(net "GND")
		)
		(pad "8" smd rect
			(at 2.921 1.949958 270)
			(size 0.3556 1.4986)
			(layers "F.Cu" "F.Mask" "F.Paste")
			(net "JTAG_DBP_TCK_PCH_R")
		)
		(pad "9" smd rect
			(at 2.921 1.299972 270)
			(size 0.3556 1.4986)
			(layers "F.Cu" "F.Mask" "F.Paste")
			(net "FM_BMC_EN_DET")
		)
		(pad "10" smd rect
			(at 2.921 0.649986 270)
			(size 0.3556 1.4986)
			(layers "F.Cu" "F.Mask" "F.Paste")
			(net "JTAG_BMC_PCH_TCK")
		)
		(pad "11" smd rect
			(at 2.921 0 270)
			(size 0.3556 1.4986)
			(layers "F.Cu" "F.Mask" "F.Paste")
			(net "TP_JTAG_BMC_4B")
		)
		(pad "12" smd rect
			(at 2.921 -0.649986 270)
			(size 0.3556 1.4986)
			(layers "F.Cu" "F.Mask" "F.Paste")
			(net "FM_BMC_EN_DET")
		)
		(pad "13" smd rect
			(at 2.921 -1.299972 270)
			(size 0.3556 1.4986)
			(layers "F.Cu" "F.Mask" "F.Paste")
			(net "PD_JTAG_BMC_NTRST_N")
		)
		(pad "14" smd rect
			(at 2.921 -1.949958 270)
			(size 0.3556 1.4986)
			(layers "F.Cu" "F.Mask" "F.Paste")
			(net "P3V3_AUX")
		)
	)
	(footprint ""
		(layer "F.Cu")
		(at 130.399028 -341.729822 90)
		(property "Reference" "PR1791"
			(at 0 0 90)
			(layer "F.SilkS")
			(hide yes)
			(effects
				(font
					(size 1.27 1.27)
				)
			)
		)
		(property "Value" ""
			(at 0 0 90)
			(layer "F.Fab")
			(effects
				(font
					(size 1.27 1.27)
				)
			)
		)
		(duplicate_pad_numbers_are_jumpers no)
		(fp_line
			(start 0.7874 -0.4064)
			(end 0.7874 0.4064)
			(stroke
				(width 0.1524)
				(type default)
			)
			(layer "F.SilkS")
		)
		(fp_line
			(start -0.7874 -0.4064)
			(end 0.7874 -0.4064)
			(stroke
				(width 0.1524)
				(type default)
			)
			(layer "F.SilkS")
		)
		(fp_line
			(start 0.7874 0.4064)
			(end -0.7874 0.4064)
			(stroke
				(width 0.1524)
				(type default)
			)
			(layer "F.SilkS")
		)
		(fp_line
			(start -0.7874 0.4064)
			(end -0.7874 -0.4064)
			(stroke
				(width 0.1524)
				(type default)
			)
			(layer "F.SilkS")
		)
		(fp_line
			(start -0.12065 -0.305054)
			(end -0.12065 -0.2794)
			(stroke
				(width 0.1)
				(type default)
			)
			(layer "F.Fab")
		)
		(fp_line
			(start -0.67945 -0.305054)
			(end -0.12065 -0.305054)
			(stroke
				(width 0.1)
				(type default)
			)
			(layer "F.Fab")
		)
		(fp_line
			(start 0.67945 -0.3048)
			(end 0.67945 0.3048)
			(stroke
				(width 0.1)
				(type default)
			)
			(layer "F.Fab")
		)
		(fp_line
			(start 0.12065 -0.3048)
			(end 0.67945 -0.3048)
			(stroke
				(width 0.1)
				(type default)
			)
			(layer "F.Fab")
		)
		(fp_line
			(start 0.12065 -0.2794)
			(end 0.12065 -0.3048)
			(stroke
				(width 0.1)
				(type default)
			)
			(layer "F.Fab")
		)
		(fp_line
			(start -0.12065 -0.2794)
			(end 0.12065 -0.2794)
			(stroke
				(width 0.1)
				(type default)
			)
			(layer "F.Fab")
		)
		(fp_line
			(start 0.120396 0.2794)
			(end -0.12065 0.2794)
			(stroke
				(width 0.1)
				(type default)
			)
			(layer "F.Fab")
		)
		(fp_line
			(start -0.12065 0.2794)
			(end -0.12065 0.3048)
			(stroke
				(width 0.1)
				(type default)
			)
			(layer "F.Fab")
		)
		(fp_line
			(start 0.67945 0.3048)
			(end 0.120396 0.3048)
			(stroke
				(width 0.1)
				(type default)
			)
			(layer "F.Fab")
		)
		(fp_line
			(start 0.120396 0.3048)
			(end 0.120396 0.2794)
			(stroke
				(width 0.1)
				(type default)
			)
			(layer "F.Fab")
		)
		(fp_line
			(start -0.12065 0.3048)
			(end -0.67945 0.3048)
			(stroke
				(width 0.1)
				(type default)
			)
			(layer "F.Fab")
		)
		(fp_line
			(start -0.67945 0.3048)
			(end -0.67945 -0.305054)
			(stroke
				(width 0.1)
				(type default)
			)
			(layer "F.Fab")
		)
		(pad "1" smd circle
			(at -0.40005 0 90)
			(size 0 0)
			(layers "F.Cu" "F.Mask" "F.Paste")
			(net "SW_PVCCIN_CPU1_BOOT5")
		)
		(pad "2" smd circle
			(at 0.40005 0 90)
			(size 0 0)
			(layers "F.Cu" "F.Mask" "F.Paste")
			(net "SW_PVCCIN_CPU1_BOOT5_R")
		)
	)
)
